(kicad_pcb
	(version 20260206)
	(generator "pcbnew")
	(generator_version "10.0")
	(general
		(thickness 1.6)
		(legacy_teardrops no)
	)
	(paper "A4")
	(title_block
		(title "Bryce Canyon_F.DPB_16315-1-OCP.brd")
		(comment 1 "Bryce Canyon / footprints 2124-2132 of 2223")
	)
	(layers
		(0 "F.Cu" signal "TOP")
		(4 "In1.Cu" signal "L2GND")
		(6 "In2.Cu" signal "L3")
		(8 "In3.Cu" signal "L4GND")
		(10 "In4.Cu" signal "L5")
		(12 "In5.Cu" signal "L6VCC")
		(14 "In6.Cu" signal "L7VCC")
		(16 "In7.Cu" signal "L8")
		(18 "In8.Cu" signal "L9GND")
		(20 "In9.Cu" signal "L10")
		(22 "In10.Cu" signal "L11GND")
		(2 "B.Cu" signal "BOTTOM")
		(9 "F.Adhes" user "F.Adhesive")
		(11 "B.Adhes" user "B.Adhesive")
		(13 "F.Paste" user "Package Geometry/Pastemask Top")
		(15 "B.Paste" user "Package Geometry/Pastemask Bottom")
		(5 "F.SilkS" user "Ref Des/Silkscreen Top")
		(7 "B.SilkS" user "Ref Des/Silkscreen Bottom")
		(1 "F.Mask" user "Board Geometry/Soldermask Top")
		(3 "B.Mask" user "Board Geometry/Soldermask Bottom")
		(17 "Dwgs.User" user "User.Drawings")
		(19 "Cmts.User" user "User.Comments")
		(21 "Eco1.User" user "User.Eco1")
		(23 "Eco2.User" user "User.Eco2")
		(25 "Edge.Cuts" user "Board Geometry/Outline")
		(27 "Margin" user)
		(31 "F.CrtYd" user "Package Geometry/Place Bound Top")
		(29 "B.CrtYd" user "Package Geometry/Place Bound Bottom")
		(35 "F.Fab" user "Ref Des/Assembly Top")
		(33 "B.Fab" user "Ref Des/Assembly Bottom")
	)
	(footprint ""
		(layer "B.Cu")
		(at 69.1134 -147.5486 180)
		(property "Reference" "C630"
			(at 0 0 0)
			(layer "B.SilkS")
			(hide yes)
			(effects
				(font
					(size 1.27 1.27)
				)
				(justify mirror)
			)
		)
		(property "Value" "SC10U16V5KX-7-GP-U"
			(at 0.0762 -6.1214 180)
			(unlocked yes)
			(layer "B.Fab")
			(hide yes)
			(effects
				(font
					(size 1.016 1.016)
					(thickness 0.1524)
				)
				(justify mirror)
			)
		)
		(property "Device Type" "C805H58"
			(at 0.0762 -8.1534 180)
			(unlocked yes)
			(layer "B.Fab")
			(hide yes)
			(effects
				(font
					(size 1.016 1.016)
					(thickness 0.1524)
				)
				(justify mirror)
			)
		)
		(duplicate_pad_numbers_are_jumpers no)
		(fp_line
			(start -0.635 0)
			(end 0.635 0)
			(stroke
				(width 0.508)
				(type default)
			)
			(layer "B.SilkS")
		)
		(fp_rect
			(start 0.9652 1.778)
			(end -0.9652 -1.778)
			(stroke
				(width 0)
				(type default)
			)
			(fill no)
			(layer "B.CrtYd")
		)
		(fp_poly
			(pts
				(xy 0.9652 -1.778) (xy -0.9652 -1.778) (xy -0.9652 1.778) (xy 0.9652 1.778)
			)
			(stroke
				(width 0)
				(type default)
			)
			(fill no)
			(layer "B.Fab")
		)
		(pad "1" smd rect
			(at 0 -0.9652)
			(size 1.397 1.143)
			(layers "B.Cu" "B.Mask" "B.Paste")
			(net "P5V_A_2")
		)
		(pad "2" smd rect
			(at 0 0.9652)
			(size 1.397 1.143)
			(layers "B.Cu" "B.Mask" "B.Paste")
			(net "GND")
		)
	)
	(footprint ""
		(layer "B.Cu")
		(at 471.885518 -205.36789 -90)
		(property "Reference" "C664"
			(at 0 0 90)
			(layer "B.SilkS")
			(hide yes)
			(effects
				(font
					(size 1.27 1.27)
				)
				(justify mirror)
			)
		)
		(property "Value" "SC10U16V5KX-7-GP-U"
			(at 0.0762 -6.1214 270)
			(unlocked yes)
			(layer "B.Fab")
			(hide yes)
			(effects
				(font
					(size 1.016 1.016)
					(thickness 0.1524)
				)
				(justify mirror)
			)
		)
		(property "Device Type" "C805H58"
			(at 0.0762 -8.1534 270)
			(unlocked yes)
			(layer "B.Fab")
			(hide yes)
			(effects
				(font
					(size 1.016 1.016)
					(thickness 0.1524)
				)
				(justify mirror)
			)
		)
		(duplicate_pad_numbers_are_jumpers no)
		(fp_line
			(start -0.635 0)
			(end 0.635 0)
			(stroke
				(width 0.508)
				(type default)
			)
			(layer "B.SilkS")
		)
		(fp_rect
			(start 0.9652 1.778)
			(end -0.9652 -1.778)
			(stroke
				(width 0)
				(type default)
			)
			(fill no)
			(layer "B.CrtYd")
		)
		(fp_poly
			(pts
				(xy 0.9652 -1.778) (xy -0.9652 -1.778) (xy -0.9652 1.778) (xy 0.9652 1.778)
			)
			(stroke
				(width 0)
				(type default)
			)
			(fill no)
			(layer "B.Fab")
		)
		(pad "1" smd rect
			(at 0 -0.9652 90)
			(size 1.397 1.143)
			(layers "B.Cu" "B.Mask" "B.Paste")
			(net "P5V_A_4")
		)
		(pad "2" smd rect
			(at 0 0.9652 90)
			(size 1.397 1.143)
			(layers "B.Cu" "B.Mask" "B.Paste")
			(net "GND")
		)
	)
	(footprint ""
		(layer "B.Cu")
		(at 20.1422 -246.7864 180)
		(property "Reference" "C601"
			(at 0 0 0)
			(layer "B.SilkS")
			(hide yes)
			(effects
				(font
					(size 1.27 1.27)
				)
				(justify mirror)
			)
		)
		(property "Value" "SC10U16V5KX-7-GP-U"
			(at 0.0762 -6.1214 180)
			(unlocked yes)
			(layer "B.Fab")
			(hide yes)
			(effects
				(font
					(size 1.016 1.016)
					(thickness 0.1524)
				)
				(justify mirror)
			)
		)
		(property "Device Type" "C805H58"
			(at 0.0762 -8.1534 180)
			(unlocked yes)
			(layer "B.Fab")
			(hide yes)
			(effects
				(font
					(size 1.016 1.016)
					(thickness 0.1524)
				)
				(justify mirror)
			)
		)
		(duplicate_pad_numbers_are_jumpers no)
		(fp_line
			(start -0.635 0)
			(end 0.635 0)
			(stroke
				(width 0.508)
				(type default)
			)
			(layer "B.SilkS")
		)
		(fp_rect
			(start 0.9652 1.778)
			(end -0.9652 -1.778)
			(stroke
				(width 0)
				(type default)
			)
			(fill no)
			(layer "B.CrtYd")
		)
		(fp_poly
			(pts
				(xy 0.9652 -1.778) (xy -0.9652 -1.778) (xy -0.9652 1.778) (xy 0.9652 1.778)
			)
			(stroke
				(width 0)
				(type default)
			)
			(fill no)
			(layer "B.Fab")
		)
		(pad "1" smd rect
			(at 0 -0.9652)
			(size 1.397 1.143)
			(layers "B.Cu" "B.Mask" "B.Paste")
			(net "P12V_A_VIN_U20")
		)
		(pad "2" smd rect
			(at 0 0.9652)
			(size 1.397 1.143)
			(layers "B.Cu" "B.Mask" "B.Paste")
			(net "GND")
		)
	)
	(footprint ""
		(layer "B.Cu")
		(at 479.552 -225.806)
		(property "Reference" "R1267"
			(at 0 0 0)
			(layer "B.SilkS")
			(hide yes)
			(effects
				(font
					(size 1.27 1.27)
				)
				(justify mirror)
			)
		)
		(property "Value" "10KR2F-2-GP"
			(at -0.064008 -3.993896 0)
			(unlocked yes)
			(layer "B.Fab")
			(hide yes)
			(effects
				(font
					(size 1.016 1.016)
					(thickness 0.1524)
				)
				(justify mirror)
			)
		)
		(property "Device Type" "R402H16"
			(at -0.064008 -5.517896 0)
			(unlocked yes)
			(layer "B.Fab")
			(hide yes)
			(effects
				(font
					(size 1.016 1.016)
					(thickness 0.1524)
				)
				(justify mirror)
			)
		)
		(duplicate_pad_numbers_are_jumpers no)
		(fp_line
			(start -0.508 -0.9398)
			(end 0.508 -0.9398)
			(stroke
				(width 0.1524)
				(type default)
			)
			(layer "B.SilkS")
		)
		(fp_line
			(start 0.508 -0.9398)
			(end 0.508 0.9398)
			(stroke
				(width 0.1524)
				(type default)
			)
			(layer "B.SilkS")
		)
		(fp_rect
			(start 0.508 0.9398)
			(end -0.508 -0.9398)
			(stroke
				(width 0)
				(type default)
			)
			(fill no)
			(layer "B.CrtYd")
		)
		(fp_rect
			(start 0.508 0.9398)
			(end -0.508 -0.9398)
			(stroke
				(width 0)
				(type default)
			)
			(fill no)
			(layer "B.Fab")
		)
		(pad "1" smd custom
			(at 0 -0.4445 180)
			(size 0.1397 0.1397)
			(layers "B.Cu" "B.Mask" "B.Paste")
			(net "P5V_A_4")
			(options
				(clearance outline)
				(anchor circle)
			)
			(primitives
				(gr_poly
					(pts
						(arc
							(start -0.1778 0.2794)
							(mid -0.249642 0.249642)
							(end -0.2794 0.1778)
						)
						(arc
							(start -0.2794 -0.1778)
							(mid -0.249642 -0.249642)
							(end -0.1778 -0.2794)
						)
						(arc
							(start 0.1778 -0.2794)
							(mid 0.249642 -0.249642)
							(end 0.2794 -0.1778)
						)
						(arc
							(start 0.2794 0.1778)
							(mid 0.249642 0.249642)
							(end 0.1778 0.2794)
						)
					)
					(width 0)
					(fill yes)
				)
			)
		)
		(pad "2" smd custom
			(at 0 0.4445 180)
			(size 0.1397 0.1397)
			(layers "B.Cu" "B.Mask" "B.Paste")
			(net "P5V_A_4_PGOOD")
			(options
				(clearance outline)
				(anchor circle)
			)
			(primitives
				(gr_poly
					(pts
						(arc
							(start -0.1778 0.2794)
							(mid -0.249642 0.249642)
							(end -0.2794 0.1778)
						)
						(arc
							(start -0.2794 -0.1778)
							(mid -0.249642 -0.249642)
							(end -0.1778 -0.2794)
						)
						(arc
							(start 0.1778 -0.2794)
							(mid 0.249642 -0.249642)
							(end 0.2794 -0.1778)
						)
						(arc
							(start 0.2794 0.1778)
							(mid 0.249642 0.249642)
							(end 0.1778 0.2794)
						)
					)
					(width 0)
					(fill yes)
				)
			)
		)
	)
	(footprint ""
		(layer "B.Cu")
		(at 474.091 -241.427 90)
		(property "Reference" "C649"
			(at 0 0 90)
			(layer "B.SilkS")
			(hide yes)
			(effects
				(font
					(size 1.27 1.27)
				)
				(justify mirror)
			)
		)
		(property "Value" "SC10U16V5KX-7-GP-U"
			(at 0.0762 -6.1214 90)
			(unlocked yes)
			(layer "B.Fab")
			(hide yes)
			(effects
				(font
					(size 1.016 1.016)
					(thickness 0.1524)
				)
				(justify mirror)
			)
		)
		(property "Device Type" "C805H58"
			(at 0.0762 -8.1534 90)
			(unlocked yes)
			(layer "B.Fab")
			(hide yes)
			(effects
				(font
					(size 1.016 1.016)
					(thickness 0.1524)
				)
				(justify mirror)
			)
		)
		(duplicate_pad_numbers_are_jumpers no)
		(fp_line
			(start -0.635 0)
			(end 0.635 0)
			(stroke
				(width 0.508)
				(type default)
			)
			(layer "B.SilkS")
		)
		(fp_rect
			(start 0.9652 1.778)
			(end -0.9652 -1.778)
			(stroke
				(width 0)
				(type default)
			)
			(fill no)
			(layer "B.CrtYd")
		)
		(fp_poly
			(pts
				(xy 0.9652 -1.778) (xy -0.9652 -1.778) (xy -0.9652 1.778) (xy 0.9652 1.778)
			)
			(stroke
				(width 0)
				(type default)
			)
			(fill no)
			(layer "B.Fab")
		)
		(pad "1" smd rect
			(at 0 -0.9652 270)
			(size 1.397 1.143)
			(layers "B.Cu" "B.Mask" "B.Paste")
			(net "P12V_A_VIN_U27")
		)
		(pad "2" smd rect
			(at 0 0.9652 270)
			(size 1.397 1.143)
			(layers "B.Cu" "B.Mask" "B.Paste")
			(net "GND")
		)
	)
	(footprint ""
		(layer "B.Cu")
		(at 192.206118 -223.441006)
		(property "Reference" "R1281"
			(at 0 0 0)
			(layer "B.SilkS")
			(hide yes)
			(effects
				(font
					(size 1.27 1.27)
				)
				(justify mirror)
			)
		)
		(property "Value" "2D2R3-1-U-GP"
			(at 0.0254 -2.5146 0)
			(unlocked yes)
			(layer "B.Fab")
			(hide yes)
			(effects
				(font
					(size 1.016 1.016)
					(thickness 0.1524)
				)
				(justify mirror)
			)
		)
		(property "Device Type" "R603H22"
			(at 0.0254 -4.0386 0)
			(unlocked yes)
			(layer "B.Fab")
			(hide yes)
			(effects
				(font
					(size 1.016 1.016)
					(thickness 0.1524)
				)
				(justify mirror)
			)
		)
		(duplicate_pad_numbers_are_jumpers no)
		(fp_line
			(start -0.2032 0)
			(end -0.4826 0)
			(stroke
				(width 0.2032)
				(type default)
			)
			(layer "B.SilkS")
		)
		(fp_line
			(start 0.4826 0)
			(end 0.2032 0)
			(stroke
				(width 0.2032)
				(type default)
			)
			(layer "B.SilkS")
		)
		(fp_rect
			(start 0.5842 1.3335)
			(end -0.5842 -1.3335)
			(stroke
				(width 0)
				(type default)
			)
			(fill no)
			(layer "B.CrtYd")
		)
		(fp_rect
			(start 0.5842 1.3335)
			(end -0.5842 -1.3335)
			(stroke
				(width 0)
				(type default)
			)
			(fill no)
			(layer "B.Fab")
		)
		(pad "1" smd custom
			(at 0 -0.762 180)
			(size 0.2159 0.2159)
			(layers "B.Cu" "B.Mask" "B.Paste")
			(net "P3V3_STBY_VCC")
			(options
				(clearance outline)
				(anchor circle)
			)
			(primitives
				(gr_poly
					(pts
						(arc
							(start -0.3302 0.4318)
							(mid -0.402042 0.402042)
							(end -0.4318 0.3302)
						)
						(arc
							(start -0.4318 -0.3302)
							(mid -0.402042 -0.402042)
							(end -0.3302 -0.4318)
						)
						(arc
							(start 0.3302 -0.4318)
							(mid 0.402042 -0.402042)
							(end 0.4318 -0.3302)
						)
						(arc
							(start 0.4318 0.3302)
							(mid 0.402042 0.402042)
							(end 0.3302 0.4318)
						)
					)
					(width 0)
					(fill yes)
				)
			)
		)
		(pad "2" smd custom
			(at 0 0.762 180)
			(size 0.2159 0.2159)
			(layers "B.Cu" "B.Mask" "B.Paste")
			(net "P12V_A")
			(options
				(clearance outline)
				(anchor circle)
			)
			(primitives
				(gr_poly
					(pts
						(arc
							(start -0.3302 0.4318)
							(mid -0.402042 0.402042)
							(end -0.4318 0.3302)
						)
						(arc
							(start -0.4318 -0.3302)
							(mid -0.402042 -0.402042)
							(end -0.3302 -0.4318)
						)
						(arc
							(start 0.3302 -0.4318)
							(mid 0.402042 -0.402042)
							(end 0.4318 -0.3302)
						)
						(arc
							(start 0.4318 0.3302)
							(mid 0.402042 0.402042)
							(end 0.3302 0.4318)
						)
					)
					(width 0)
					(fill yes)
				)
			)
		)
	)
	(footprint ""
		(layer "B.Cu")
		(at 16.129 -246.8118)
		(property "Reference" "L1"
			(at 0 0 0)
			(layer "B.SilkS")
			(hide yes)
			(effects
				(font
					(size 1.27 1.27)
				)
				(justify mirror)
			)
		)
		(property "Value" "BLM21PG220SN1DGP"
			(at -0.0254 -5.6896 0)
			(unlocked yes)
			(layer "B.Fab")
			(hide yes)
			(effects
				(font
					(size 1.016 1.016)
					(thickness 0.1524)
				)
				(justify mirror)
			)
		)
		(property "Device Type" "L20125H42"
			(at -0.0254 -7.5946 0)
			(unlocked yes)
			(layer "B.Fab")
			(hide yes)
			(effects
				(font
					(size 1.016 1.016)
					(thickness 0.1524)
				)
				(justify mirror)
			)
		)
		(duplicate_pad_numbers_are_jumpers no)
		(fp_line
			(start -0.9144 -1.7018)
			(end 0.9144 -1.7018)
			(stroke
				(width 0.1524)
				(type default)
			)
			(layer "B.SilkS")
		)
		(fp_line
			(start -0.9144 1.7018)
			(end -0.9144 -1.7018)
			(stroke
				(width 0.1524)
				(type default)
			)
			(layer "B.SilkS")
		)
		(fp_line
			(start 0.9144 -1.7018)
			(end 0.9144 1.7018)
			(stroke
				(width 0.1524)
				(type default)
			)
			(layer "B.SilkS")
		)
		(fp_line
			(start 0.9144 1.7018)
			(end -0.9144 1.7018)
			(stroke
				(width 0.1524)
				(type default)
			)
			(layer "B.SilkS")
		)
		(fp_rect
			(start 1.0033 1.778)
			(end -1.0033 -1.778)
			(stroke
				(width 0)
				(type default)
			)
			(fill no)
			(layer "B.CrtYd")
		)
		(fp_poly
			(pts
				(xy 1.0033 -1.778) (xy -1.0033 -1.778) (xy -1.0033 1.778) (xy 1.0033 1.778)
			)
			(stroke
				(width 0)
				(type default)
			)
			(fill no)
			(layer "B.Fab")
		)
		(pad "1" smd rect
			(at 0 -0.9652 180)
			(size 1.397 1.143)
			(layers "B.Cu" "B.Mask" "B.Paste")
			(net "P12V_A")
		)
		(pad "2" smd rect
			(at 0 0.9652 180)
			(size 1.397 1.143)
			(layers "B.Cu" "B.Mask" "B.Paste")
			(net "P12V_A_VIN_U20")
		)
	)
	(footprint ""
		(layer "B.Cu")
		(at 38.876224 -254.711454 -90)
		(property "Reference" "C609"
			(at 0 0 90)
			(layer "B.SilkS")
			(hide yes)
			(effects
				(font
					(size 1.27 1.27)
				)
				(justify mirror)
			)
		)
		(property "Value" "SC470P50V2KX-3GP"
			(at -1.1811 -2.7051 270)
			(unlocked yes)
			(layer "B.Fab")
			(hide yes)
			(effects
				(font
					(size 1.016 1.016)
					(thickness 0.1524)
				)
				(justify mirror)
			)
		)
		(property "Device Type" "C402H22"
			(at -1.1811 -4.2291 270)
			(unlocked yes)
			(layer "B.Fab")
			(hide yes)
			(effects
				(font
					(size 1.016 1.016)
					(thickness 0.1524)
				)
				(justify mirror)
			)
		)
		(duplicate_pad_numbers_are_jumpers no)
		(fp_rect
			(start 0.4318 0.9525)
			(end -0.4318 -0.9525)
			(stroke
				(width 0)
				(type default)
			)
			(fill no)
			(layer "B.CrtYd")
		)
		(fp_rect
			(start 0.4318 0.9525)
			(end -0.4318 -0.9525)
			(stroke
				(width 0)
				(type default)
			)
			(fill no)
			(layer "B.Fab")
		)
		(pad "1" smd custom
			(at 0 -0.4445 90)
			(size 0.1524 0.1524)
			(layers "B.Cu" "B.Mask" "B.Paste")
			(net "P5V_A_LL_R")
			(options
				(clearance outline)
				(anchor circle)
			)
			(primitives
				(gr_poly
					(pts
						(arc
							(start 0.3048 0.2032)
							(mid 0.275042 0.275042)
							(end 0.2032 0.3048)
						)
						(arc
							(start -0.2032 0.3048)
							(mid -0.275042 0.275042)
							(end -0.3048 0.2032)
						)
						(arc
							(start -0.3048 -0.2032)
							(mid -0.275042 -0.275042)
							(end -0.2032 -0.3048)
						)
						(arc
							(start 0.2032 -0.3048)
							(mid 0.275042 -0.275042)
							(end 0.3048 -0.2032)
						)
					)
					(width 0)
					(fill yes)
				)
			)
		)
		(pad "2" smd custom
			(at 0 0.4445 90)
			(size 0.1524 0.1524)
			(layers "B.Cu" "B.Mask" "B.Paste")
			(net "P5V_A_VFB")
			(options
				(clearance outline)
				(anchor circle)
			)
			(primitives
				(gr_poly
					(pts
						(arc
							(start 0.3048 0.2032)
							(mid 0.275042 0.275042)
							(end 0.2032 0.3048)
						)
						(arc
							(start -0.2032 0.3048)
							(mid -0.275042 0.275042)
							(end -0.3048 0.2032)
						)
						(arc
							(start -0.3048 -0.2032)
							(mid -0.275042 -0.275042)
							(end -0.2032 -0.3048)
						)
						(arc
							(start 0.2032 -0.3048)
							(mid 0.275042 -0.275042)
							(end 0.3048 -0.2032)
						)
					)
					(width 0)
					(fill yes)
				)
			)
		)
	)
	(footprint ""
		(layer "B.Cu")
		(at 187.447936 -220.242384 180)
		(property "Reference" "R1283"
			(at 0 0 0)
			(layer "B.SilkS")
			(hide yes)
			(effects
				(font
					(size 1.27 1.27)
				)
				(justify mirror)
			)
		)
		(property "Value" "10KR2F-2-GP"
			(at -0.064008 -3.993896 180)
			(unlocked yes)
			(layer "B.Fab")
			(hide yes)
			(effects
				(font
					(size 1.016 1.016)
					(thickness 0.1524)
				)
				(justify mirror)
			)
		)
		(property "Device Type" "R402H16"
			(at -0.064008 -5.517896 180)
			(unlocked yes)
			(layer "B.Fab")
			(hide yes)
			(effects
				(font
					(size 1.016 1.016)
					(thickness 0.1524)
				)
				(justify mirror)
			)
		)
		(duplicate_pad_numbers_are_jumpers no)
		(fp_line
			(start 0.508 -0.9398)
			(end 0.508 0.9398)
			(stroke
				(width 0.1524)
				(type default)
			)
			(layer "B.SilkS")
		)
		(fp_line
			(start -0.508 -0.9398)
			(end 0.508 -0.9398)
			(stroke
				(width 0.1524)
				(type default)
			)
			(layer "B.SilkS")
		)
		(fp_rect
			(start 0.508 0.9398)
			(end -0.508 -0.9398)
			(stroke
				(width 0)
				(type default)
			)
			(fill no)
			(layer "B.CrtYd")
		)
		(fp_rect
			(start 0.508 0.9398)
			(end -0.508 -0.9398)
			(stroke
				(width 0)
				(type default)
			)
			(fill no)
			(layer "B.Fab")
		)
		(pad "1" smd custom
			(at 0 -0.4445)
			(size 0.1397 0.1397)
			(layers "B.Cu" "B.Mask" "B.Paste")
			(net "AGND_P3V3_STBY")
			(options
				(clearance outline)
				(anchor circle)
			)
			(primitives
				(gr_poly
					(pts
						(arc
							(start -0.1778 0.2794)
							(mid -0.249642 0.249642)
							(end -0.2794 0.1778)
						)
						(arc
							(start -0.2794 -0.1778)
							(mid -0.249642 -0.249642)
							(end -0.1778 -0.2794)
						)
						(arc
							(start 0.1778 -0.2794)
							(mid 0.249642 -0.249642)
							(end 0.2794 -0.1778)
						)
						(arc
							(start 0.2794 0.1778)
							(mid 0.249642 0.249642)
							(end 0.1778 0.2794)
						)
					)
					(width 0)
					(fill yes)
				)
			)
		)
		(pad "2" smd custom
			(at 0 0.4445)
			(size 0.1397 0.1397)
			(layers "B.Cu" "B.Mask" "B.Paste")
			(net "P3V3_STBY_VFB")
			(options
				(clearance outline)
				(anchor circle)
			)
			(primitives
				(gr_poly
					(pts
						(arc
							(start -0.1778 0.2794)
							(mid -0.249642 0.249642)
							(end -0.2794 0.1778)
						)
						(arc
							(start -0.2794 -0.1778)
							(mid -0.249642 -0.249642)
							(end -0.1778 -0.2794)
						)
						(arc
							(start 0.1778 -0.2794)
							(mid 0.249642 -0.249642)
							(end 0.2794 -0.1778)
						)
						(arc
							(start 0.2794 0.1778)
							(mid 0.249642 0.249642)
							(end 0.1778 0.2794)
						)
					)
					(width 0)
					(fill yes)
				)
			)
		)
	)
)
